FILE_TYPE = CONNECTIVITY;
{Allegro Design Entry HDL 16.6-p007 (v16-6-112F) 10/10/2012}
"PAGE_NUMBER" = 31;
0"NC";
1"P3E_CPU0_PE2_SS_TXN<15:0>";
2"P3E_CPU0_PE2_SS_TXP<15:0>";
3"P3E_CPU0_PE2_SS_RXN<15:0>";
4"P3E_CPU0_PE2_SS_RXP<15:0>";
5"P3E_CPU0_PE2_SS_RXN<2>";
6"P3E_CPU0_PE2_SS_RXP<0>";
7"P3E_CPU0_PE2_SS_RXP<1>";
8"P3E_CPU0_PE2_SS_RXP<2>";
9"P3E_CPU0_PE2_SS_RXN<0>";
10"P3E_CPU0_PE2_SS_RXN<1>";
11"P3E_CPU0_PE2_SS_RXN<3>";
12"P3E_CPU0_PE2_SS_RXP<3>";
13"P3E_CPU0_PE2_SS_RXP<4>";
14"P3E_CPU0_PE2_SS_RXP<5>";
15"P3E_CPU0_PE2_SS_RXP<6>";
16"P3E_CPU0_PE2_SS_RXP<7>";
17"P3E_CPU0_PE2_SS_RXP<8>";
18"P3E_CPU0_PE2_SS_RXP<9>";
19"P3E_CPU0_PE2_SS_RXP<10>";
20"P3E_CPU0_PE2_SS_RXP<11>";
21"P3E_CPU0_PE2_SS_RXP<12>";
22"P3E_CPU0_PE2_SS_RXP<13>";
23"P3E_CPU0_PE2_SS_RXP<14>";
24"P3E_CPU0_PE2_SS_RXP<15>";
25"P3E_CPU0_PE2_SS_RXN<4>";
26"P3E_CPU0_PE2_SS_RXN<5>";
27"P3E_CPU0_PE2_SS_RXN<6>";
28"P3E_CPU0_PE2_SS_RXN<7>";
29"P3E_CPU0_PE2_SS_RXN<8>";
30"P3E_CPU0_PE2_SS_RXN<9>";
31"P3E_CPU0_PE2_SS_RXN<10>";
32"P3E_CPU0_PE2_SS_RXN<11>";
33"P3E_CPU0_PE2_SS_RXN<12>";
34"P3E_CPU0_PE2_SS_RXN<13>";
35"P3E_CPU0_PE2_SS_RXN<14>";
36"P3E_CPU0_PE2_SS_RXN<15>";
37"P3E_CPU0_PE2_SS_TXP<0>";
38"P3E_CPU0_PE2_SS_TXP<1>";
39"P3E_CPU0_PE2_SS_TXP<2>";
40"P3E_CPU0_PE2_SS_TXN<0>";
41"P3E_CPU0_PE2_SS_TXN<1>";
42"P3E_CPU0_PE2_SS_TXN<2>";
43"P3E_CPU0_PE2_SS_TXN<3>";
44"P3E_CPU0_PE2_SS_TXP<3>";
45"P3E_CPU0_PE2_SS_TXP<4>";
46"P3E_CPU0_PE2_SS_TXP<5>";
47"P3E_CPU0_PE2_SS_TXP<6>";
48"P3E_CPU0_PE2_SS_TXP<7>";
49"P3E_CPU0_PE2_SS_TXP<8>";
50"P3E_CPU0_PE2_SS_TXP<9>";
51"P3E_CPU0_PE2_SS_TXP<10>";
52"P3E_CPU0_PE2_SS_TXP<11>";
53"P3E_CPU0_PE2_SS_TXP<12>";
54"P3E_CPU0_PE2_SS_TXP<13>";
55"P3E_CPU0_PE2_SS_TXP<14>";
56"P3E_CPU0_PE2_SS_TXP<15>";
57"P3E_CPU0_PE2_SS_TXN<4>";
58"P3E_CPU0_PE2_SS_TXN<5>";
59"P3E_CPU0_PE2_SS_TXN<6>";
60"P3E_CPU0_PE2_SS_TXN<7>";
61"P3E_CPU0_PE2_SS_TXN<8>";
62"P3E_CPU0_PE2_SS_TXN<9>";
63"P3E_CPU0_PE2_SS_TXN<10>";
64"P3E_CPU0_PE2_SS_TXN<11>";
65"P3E_CPU0_PE2_SS_TXN<12>";
66"P3E_CPU0_PE2_SS_TXN<13>";
67"P3E_CPU0_PE2_SS_TXN<14>";
68"P3E_CPU0_PE2_SS_TXN<15>";
%"TAP"
"1","(-5450,1950)","2","mstr_standard","I10";
;
HDL_TAP"TRUE"
BODY_TYPE"PLUMBING"
CDS_LIB"mstr_standard";
"B \NAC \NWC"4;
"S \NAC"
BN"1"7;
%"TAP"
"1","(-5300,2650)","2","mstr_standard","I100";
;
HDL_TAP"TRUE"
BODY_TYPE"PLUMBING"
CDS_LIB"mstr_standard";
"B \NAC \NWC"3;
"S \NAC"
BN"8"29;
%"TAP"
"1","(-5450,3000)","2","mstr_standard","I101";
;
HDL_TAP"TRUE"
BODY_TYPE"PLUMBING"
CDS_LIB"mstr_standard";
"B \NAC \NWC"4;
"S \NAC"
BN"10"19;
%"TAP"
"1","(-5450,2950)","2","mstr_standard","I102";
;
HDL_TAP"TRUE"
BODY_TYPE"PLUMBING"
CDS_LIB"mstr_standard";
"B \NAC \NWC"4;
"S \NAC"
BN"9"18;
%"TAP"
"1","(-5450,2900)","2","mstr_standard","I103";
;
HDL_TAP"TRUE"
BODY_TYPE"PLUMBING"
CDS_LIB"mstr_standard";
"B \NAC \NWC"4;
"S \NAC"
BN"8"17;
%"SKX_EXT_B"
"11","(-4025,2600)","0","chpset_lib","I106";
;
CDS_SEC"11"
ROOM"CPU0"
CDS_LOCATION"U5D1"
SEC"11"
SEC_TYPE"BGA1"
CDS_LIB"chpset_lib"
PACK_TYPE"BGA1"
MATERIAL"IC"
PART_NUMBER"TBD"
LOCATION"U5D1";
"PE2_TX_DP<0>"
$PN"CW4"37;
"PE2_TX_DP<1>"
$PN"CU2"38;
"PE2_TX_DP<2>"
$PN"CR2"39;
"PE2_TX_DP<3>"
$PN"CP3"44;
"PE2_TX_DP<4>"
$PN"CK1"45;
"PE2_TX_DP<5>"
$PN"CK3"46;
"PE2_TX_DP<6>"
$PN"CE2"47;
"PE2_TX_DP<7>"
$PN"CE4"48;
"PE2_TX_DP<8>"
$PN"CD3"49;
"PE2_TX_DP<9>"
$PN"BY3"50;
"PE2_TX_DP<10>"
$PN"BY5"51;
"PE2_TX_DP<11>"
$PN"BV3"52;
"PE2_TX_DP<12>"
$PN"BR4"53;
"PE2_TX_DP<13>"
$PN"BN4"54;
"PE2_TX_DP<14>"
$PN"BM3"55;
"PE2_TX_DP<15>"
$PN"BK5"56;
"PE2_TX_DN<0>"
$PN"CY3"40;
"PE2_TX_DN<1>"
$PN"CV3"41;
"PE2_TX_DN<2>"
$PN"CT1"42;
"PE2_TX_DN<3>"
$PN"CT3"43;
"PE2_TX_DN<4>"
$PN"CM1"57;
"PE2_TX_DN<5>"
$PN"CL2"58;
"PE2_TX_DN<6>"
$PN"CG2"59;
"PE2_TX_DN<7>"
$PN"CF3"60;
"PE2_TX_DN<8>"
$PN"CC2"61;
"PE2_TX_DN<9>"
$PN"CB3"62;
"PE2_TX_DN<10>"
$PN"CA4"63;
"PE2_TX_DN<11>"
$PN"BW4"64;
"PE2_TX_DN<12>"
$PN"BU4"65;
"PE2_TX_DN<13>"
$PN"BP5"66;
"PE2_TX_DN<14>"
$PN"BL4"67;
"PE2_TX_DN<15>"
$PN"BM5"68;
"PE2_RX_DP<0>"
$PN"CR8"6;
"PE2_RX_DP<1>"
$PN"CM9"7;
"PE2_RX_DP<2>"
$PN"CN8"8;
"PE2_RX_DP<3>"
$PN"CL6"12;
"PE2_RX_DP<4>"
$PN"CH7"13;
"PE2_RX_DP<5>"
$PN"CF7"14;
"PE2_RX_DP<6>"
$PN"CD7"15;
"PE2_RX_DP<7>"
$PN"CC8"16;
"PE2_RX_DP<8>"
$PN"BV9"17;
"PE2_RX_DP<9>"
$PN"BW8"18;
"PE2_RX_DP<10>"
$PN"BU6"19;
"PE2_RX_DP<11>"
$PN"BP7"20;
"PE2_RX_DP<12>"
$PN"BP9"21;
"PE2_RX_DP<13>"
$PN"BM7"22;
"PE2_RX_DP<14>"
$PN"BJ8"23;
"PE2_RX_DP<15>"
$PN"BJ10"24;
"PE2_RX_DN<0>"
$PN"CT9"9;
"PE2_RX_DN<1>"
$PN"CP9"10;
"PE2_RX_DN<2>"
$PN"CP7"5;
"PE2_RX_DN<3>"
$PN"CM7"11;
"PE2_RX_DN<4>"
$PN"CK7"25;
"PE2_RX_DN<5>"
$PN"CG8"26;
"PE2_RX_DN<6>"
$PN"CE6"27;
"PE2_RX_DN<7>"
$PN"CE8"28;
"PE2_RX_DN<8>"
$PN"BY9"29;
"PE2_RX_DN<9>"
$PN"BY7"30;
"PE2_RX_DN<10>"
$PN"BV7"31;
"PE2_RX_DN<11>"
$PN"BT7"32;
"PE2_RX_DN<12>"
$PN"BR8"33;
"PE2_RX_DN<13>"
$PN"BN8"34;
"PE2_RX_DN<14>"
$PN"BL8"35;
"PE2_RX_DN<15>"
$PN"BK9"36;
%"TAP"
"1","(-5450,2000)","2","mstr_standard","I11";
;
HDL_TAP"TRUE"
BODY_TYPE"PLUMBING"
CDS_LIB"mstr_standard";
"B \NAC \NWC"4;
"S \NAC"
BN"2"8;
%"TAP"
"1","(-5450,2400)","2","mstr_standard","I12";
;
HDL_TAP"TRUE"
BODY_TYPE"PLUMBING"
CDS_LIB"mstr_standard";
"B \NAC \NWC"4;
"S \NAC"
BN"4"13;
%"TAP"
"1","(-5300,2150)","2","mstr_standard","I13";
;
HDL_TAP"TRUE"
BODY_TYPE"PLUMBING"
CDS_LIB"mstr_standard";
"B \NAC \NWC"3;
"S \NAC"
BN"4"25;
%"TAP"
"1","(-5300,2250)","2","mstr_standard","I14";
;
HDL_TAP"TRUE"
BODY_TYPE"PLUMBING"
CDS_LIB"mstr_standard";
"B \NAC \NWC"3;
"S \NAC"
BN"6"27;
%"TAP"
"1","(-5300,2300)","2","mstr_standard","I15";
;
HDL_TAP"TRUE"
BODY_TYPE"PLUMBING"
CDS_LIB"mstr_standard";
"B \NAC \NWC"3;
"S \NAC"
BN"7"28;
%"TAP"
"1","(-5300,2200)","2","mstr_standard","I16";
;
HDL_TAP"TRUE"
BODY_TYPE"PLUMBING"
CDS_LIB"mstr_standard";
"B \NAC \NWC"3;
"S \NAC"
BN"5"26;
%"TAP"
"1","(-5450,2550)","2","mstr_standard","I17";
;
HDL_TAP"TRUE"
BODY_TYPE"PLUMBING"
CDS_LIB"mstr_standard";
"B \NAC \NWC"4;
"S \NAC"
BN"7"16;
%"TAP"
"1","(-5450,2450)","2","mstr_standard","I18";
;
HDL_TAP"TRUE"
BODY_TYPE"PLUMBING"
CDS_LIB"mstr_standard";
"B \NAC \NWC"4;
"S \NAC"
BN"5"14;
%"TAP"
"1","(-5450,2500)","2","mstr_standard","I19";
;
HDL_TAP"TRUE"
BODY_TYPE"PLUMBING"
CDS_LIB"mstr_standard";
"B \NAC \NWC"4;
"S \NAC"
BN"6"15;
%"TAP"
"1","(-5300,1650)","2","mstr_standard","I3";
;
HDL_TAP"TRUE"
BODY_TYPE"PLUMBING"
CDS_LIB"mstr_standard";
"B \NAC \NWC"3;
"S \NAC"
BN"0"9;
%"TAP"
"1","(-2675,1650)","0","mstr_standard","I36";
;
HDL_TAP"TRUE"
BODY_TYPE"PLUMBING"
CDS_LIB"mstr_standard";
"B \NAC \NWC"1;
"S \NAC"
BN"0"40;
%"TAP"
"1","(-2825,1900)","0","mstr_standard","I37";
;
HDL_TAP"TRUE"
BODY_TYPE"PLUMBING"
CDS_LIB"mstr_standard";
"B \NAC \NWC"2;
"S \NAC"
BN"0"37;
%"TAP"
"1","(-2675,1700)","0","mstr_standard","I38";
;
HDL_TAP"TRUE"
BODY_TYPE"PLUMBING"
CDS_LIB"mstr_standard";
"B \NAC \NWC"1;
"S \NAC"
BN"1"41;
%"TAP"
"1","(-2675,1750)","0","mstr_standard","I39";
;
HDL_TAP"TRUE"
BODY_TYPE"PLUMBING"
CDS_LIB"mstr_standard";
"B \NAC \NWC"1;
"S \NAC"
BN"2"42;
%"TAP"
"1","(-5300,1700)","2","mstr_standard","I4";
;
HDL_TAP"TRUE"
BODY_TYPE"PLUMBING"
CDS_LIB"mstr_standard";
"B \NAC \NWC"3;
"S \NAC"
BN"1"10;
%"TAP"
"1","(-2675,1800)","0","mstr_standard","I40";
;
HDL_TAP"TRUE"
BODY_TYPE"PLUMBING"
CDS_LIB"mstr_standard";
"B \NAC \NWC"1;
"S \NAC"
BN"3"43;
%"TAP"
"1","(-2825,1950)","0","mstr_standard","I41";
;
HDL_TAP"TRUE"
BODY_TYPE"PLUMBING"
CDS_LIB"mstr_standard";
"B \NAC \NWC"2;
"S \NAC"
BN"1"38;
%"TAP"
"1","(-2825,2000)","0","mstr_standard","I42";
;
HDL_TAP"TRUE"
BODY_TYPE"PLUMBING"
CDS_LIB"mstr_standard";
"B \NAC \NWC"2;
"S \NAC"
BN"2"39;
%"TAP"
"1","(-2825,2050)","0","mstr_standard","I43";
;
HDL_TAP"TRUE"
BODY_TYPE"PLUMBING"
CDS_LIB"mstr_standard";
"B \NAC \NWC"2;
"S \NAC"
BN"3"44;
%"TAP"
"1","(-2675,2150)","0","mstr_standard","I44";
;
HDL_TAP"TRUE"
BODY_TYPE"PLUMBING"
CDS_LIB"mstr_standard";
"B \NAC \NWC"1;
"S \NAC"
BN"4"57;
%"TAP"
"1","(-2825,2400)","0","mstr_standard","I45";
;
HDL_TAP"TRUE"
BODY_TYPE"PLUMBING"
CDS_LIB"mstr_standard";
"B \NAC \NWC"2;
"S \NAC"
BN"4"45;
%"TAP"
"1","(-2675,2200)","0","mstr_standard","I46";
;
HDL_TAP"TRUE"
BODY_TYPE"PLUMBING"
CDS_LIB"mstr_standard";
"B \NAC \NWC"1;
"S \NAC"
BN"5"58;
%"TAP"
"1","(-2675,2300)","0","mstr_standard","I47";
;
HDL_TAP"TRUE"
BODY_TYPE"PLUMBING"
CDS_LIB"mstr_standard";
"B \NAC \NWC"1;
"S \NAC"
BN"7"60;
%"TAP"
"1","(-2675,2250)","0","mstr_standard","I48";
;
HDL_TAP"TRUE"
BODY_TYPE"PLUMBING"
CDS_LIB"mstr_standard";
"B \NAC \NWC"1;
"S \NAC"
BN"6"59;
%"TAP"
"1","(-2825,2550)","0","mstr_standard","I49";
;
HDL_TAP"TRUE"
BODY_TYPE"PLUMBING"
CDS_LIB"mstr_standard";
"B \NAC \NWC"2;
"S \NAC"
BN"7"48;
%"TAP"
"1","(-5300,1750)","2","mstr_standard","I5";
;
HDL_TAP"TRUE"
BODY_TYPE"PLUMBING"
CDS_LIB"mstr_standard";
"B \NAC \NWC"3;
"S \NAC"
BN"2"5;
%"TAP"
"1","(-2825,2450)","0","mstr_standard","I50";
;
HDL_TAP"TRUE"
BODY_TYPE"PLUMBING"
CDS_LIB"mstr_standard";
"B \NAC \NWC"2;
"S \NAC"
BN"5"46;
%"TAP"
"1","(-2825,2500)","0","mstr_standard","I51";
;
HDL_TAP"TRUE"
BODY_TYPE"PLUMBING"
CDS_LIB"mstr_standard";
"B \NAC \NWC"2;
"S \NAC"
BN"6"47;
%"TAP"
"1","(-5300,1800)","2","mstr_standard","I6";
;
HDL_TAP"TRUE"
BODY_TYPE"PLUMBING"
CDS_LIB"mstr_standard";
"B \NAC \NWC"3;
"S \NAC"
BN"3"11;
%"TAP"
"1","(-5450,1900)","2","mstr_standard","I7";
;
HDL_TAP"TRUE"
BODY_TYPE"PLUMBING"
CDS_LIB"mstr_standard";
"B \NAC \NWC"4;
"S \NAC"
BN"0"6;
%"TAP"
"1","(-2675,3200)","0","mstr_standard","I72";
;
HDL_TAP"TRUE"
BODY_TYPE"PLUMBING"
CDS_LIB"mstr_standard";
"B \NAC \NWC"1;
"S \NAC"
BN"13"66;
%"TAP"
"1","(-2675,3300)","0","mstr_standard","I73";
;
HDL_TAP"TRUE"
BODY_TYPE"PLUMBING"
CDS_LIB"mstr_standard";
"B \NAC \NWC"1;
"S \NAC"
BN"15"68;
%"TAP"
"1","(-2675,3250)","0","mstr_standard","I74";
;
HDL_TAP"TRUE"
BODY_TYPE"PLUMBING"
CDS_LIB"mstr_standard";
"B \NAC \NWC"1;
"S \NAC"
BN"14"67;
%"TAP"
"1","(-2675,3150)","0","mstr_standard","I75";
;
HDL_TAP"TRUE"
BODY_TYPE"PLUMBING"
CDS_LIB"mstr_standard";
"B \NAC \NWC"1;
"S \NAC"
BN"12"65;
%"TAP"
"1","(-2825,3500)","0","mstr_standard","I76";
;
HDL_TAP"TRUE"
BODY_TYPE"PLUMBING"
CDS_LIB"mstr_standard";
"B \NAC \NWC"2;
"S \NAC"
BN"14"55;
%"TAP"
"1","(-2825,3550)","0","mstr_standard","I77";
;
HDL_TAP"TRUE"
BODY_TYPE"PLUMBING"
CDS_LIB"mstr_standard";
"B \NAC \NWC"2;
"S \NAC"
BN"15"56;
%"TAP"
"1","(-2825,3450)","0","mstr_standard","I78";
;
HDL_TAP"TRUE"
BODY_TYPE"PLUMBING"
CDS_LIB"mstr_standard";
"B \NAC \NWC"2;
"S \NAC"
BN"13"54;
%"TAP"
"1","(-2825,3400)","0","mstr_standard","I79";
;
HDL_TAP"TRUE"
BODY_TYPE"PLUMBING"
CDS_LIB"mstr_standard";
"B \NAC \NWC"2;
"S \NAC"
BN"12"53;
%"TAP"
"1","(-2825,3050)","0","mstr_standard","I80";
;
HDL_TAP"TRUE"
BODY_TYPE"PLUMBING"
CDS_LIB"mstr_standard";
"B \NAC \NWC"2;
"S \NAC"
BN"11"52;
%"TAP"
"1","(-2675,2800)","0","mstr_standard","I81";
;
HDL_TAP"TRUE"
BODY_TYPE"PLUMBING"
CDS_LIB"mstr_standard";
"B \NAC \NWC"1;
"S \NAC"
BN"11"64;
%"TAP"
"1","(-2675,2750)","0","mstr_standard","I82";
;
HDL_TAP"TRUE"
BODY_TYPE"PLUMBING"
CDS_LIB"mstr_standard";
"B \NAC \NWC"1;
"S \NAC"
BN"10"63;
%"TAP"
"1","(-2675,2700)","0","mstr_standard","I83";
;
HDL_TAP"TRUE"
BODY_TYPE"PLUMBING"
CDS_LIB"mstr_standard";
"B \NAC \NWC"1;
"S \NAC"
BN"9"62;
%"TAP"
"1","(-2675,2650)","0","mstr_standard","I84";
;
HDL_TAP"TRUE"
BODY_TYPE"PLUMBING"
CDS_LIB"mstr_standard";
"B \NAC \NWC"1;
"S \NAC"
BN"8"61;
%"TAP"
"1","(-2825,3000)","0","mstr_standard","I85";
;
HDL_TAP"TRUE"
BODY_TYPE"PLUMBING"
CDS_LIB"mstr_standard";
"B \NAC \NWC"2;
"S \NAC"
BN"10"51;
%"TAP"
"1","(-2825,2950)","0","mstr_standard","I86";
;
HDL_TAP"TRUE"
BODY_TYPE"PLUMBING"
CDS_LIB"mstr_standard";
"B \NAC \NWC"2;
"S \NAC"
BN"9"50;
%"TAP"
"1","(-2825,2900)","0","mstr_standard","I87";
;
HDL_TAP"TRUE"
BODY_TYPE"PLUMBING"
CDS_LIB"mstr_standard";
"B \NAC \NWC"2;
"S \NAC"
BN"8"49;
%"TAP"
"1","(-5300,3300)","2","mstr_standard","I88";
;
HDL_TAP"TRUE"
BODY_TYPE"PLUMBING"
CDS_LIB"mstr_standard";
"B \NAC \NWC"3;
"S \NAC"
BN"15"36;
%"TAP"
"1","(-5300,3250)","2","mstr_standard","I89";
;
HDL_TAP"TRUE"
BODY_TYPE"PLUMBING"
CDS_LIB"mstr_standard";
"B \NAC \NWC"3;
"S \NAC"
BN"14"35;
%"TAP"
"1","(-5450,2050)","2","mstr_standard","I9";
;
HDL_TAP"TRUE"
BODY_TYPE"PLUMBING"
CDS_LIB"mstr_standard";
"B \NAC \NWC"4;
"S \NAC"
BN"3"12;
%"TAP"
"1","(-5300,3200)","2","mstr_standard","I90";
;
HDL_TAP"TRUE"
BODY_TYPE"PLUMBING"
CDS_LIB"mstr_standard";
"B \NAC \NWC"3;
"S \NAC"
BN"13"34;
%"TAP"
"1","(-5300,3150)","2","mstr_standard","I91";
;
HDL_TAP"TRUE"
BODY_TYPE"PLUMBING"
CDS_LIB"mstr_standard";
"B \NAC \NWC"3;
"S \NAC"
BN"12"33;
%"TAP"
"1","(-5450,3550)","2","mstr_standard","I92";
;
HDL_TAP"TRUE"
BODY_TYPE"PLUMBING"
CDS_LIB"mstr_standard";
"B \NAC \NWC"4;
"S \NAC"
BN"15"24;
%"TAP"
"1","(-5450,3500)","2","mstr_standard","I93";
;
HDL_TAP"TRUE"
BODY_TYPE"PLUMBING"
CDS_LIB"mstr_standard";
"B \NAC \NWC"4;
"S \NAC"
BN"14"23;
%"TAP"
"1","(-5450,3450)","2","mstr_standard","I94";
;
HDL_TAP"TRUE"
BODY_TYPE"PLUMBING"
CDS_LIB"mstr_standard";
"B \NAC \NWC"4;
"S \NAC"
BN"13"22;
%"TAP"
"1","(-5450,3400)","2","mstr_standard","I95";
;
HDL_TAP"TRUE"
BODY_TYPE"PLUMBING"
CDS_LIB"mstr_standard";
"B \NAC \NWC"4;
"S \NAC"
BN"12"21;
%"TAP"
"1","(-5450,3050)","2","mstr_standard","I96";
;
HDL_TAP"TRUE"
BODY_TYPE"PLUMBING"
CDS_LIB"mstr_standard";
"B \NAC \NWC"4;
"S \NAC"
BN"11"20;
%"TAP"
"1","(-5300,2800)","2","mstr_standard","I97";
;
HDL_TAP"TRUE"
BODY_TYPE"PLUMBING"
CDS_LIB"mstr_standard";
"B \NAC \NWC"3;
"S \NAC"
BN"11"32;
%"TAP"
"1","(-5300,2700)","2","mstr_standard","I98";
;
HDL_TAP"TRUE"
BODY_TYPE"PLUMBING"
CDS_LIB"mstr_standard";
"B \NAC \NWC"3;
"S \NAC"
BN"9"30;
%"TAP"
"1","(-5300,2750)","2","mstr_standard","I99";
;
HDL_TAP"TRUE"
BODY_TYPE"PLUMBING"
CDS_LIB"mstr_standard";
"B \NAC \NWC"3;
"S \NAC"
BN"10"31;
END.
